#ISCELL
  mstr_misc dns *
  *
#ISCELL
  pure_quanta quanta_title_block_c *
  *
#CELL
  pure_quanta q_res *
  page177_i100
#CELL
  pure_quanta q_res *
  page177_i102
#CELL
  pure_quanta q_res *
  page177_i106
#ISCELL
  standard offpage *
  page177_i108
#ISCELL
  standard offpage *
  page177_i110
#ISCELL
  standard offpage *
  page177_i111
#ISCELL
  standard offpage *
  page177_i112
#ISCELL
  standard offpage *
  page177_i113
#ISCELL
  standard offpage *
  page177_i114
#ISCELL
  standard offpage *
  page177_i115
#ISCELL
  logical_power universal_power *
  page177_i116
#ISCELL
  standard offpage *
  page177_i117
#CELL
  pure_quanta q_res *
  page177_i118
#CELL
  pure_quanta q_res *
  page177_i119
#ISCELL
  standard offpage *
  page177_i12
#CELL
  pure_quanta q_res *
  page177_i120
#CELL
  pure_quanta q_res *
  page177_i121
#ISCELL
  standard offpage *
  page177_i122
#CELL
  pure_quanta mosfet_nch_gds_esd_protected *
  page177_i123
#CELL
  pure_quanta mosfet_nch_gds_esd_protected *
  page177_i124
#CELL
  pure_quanta q_res *
  page177_i125
#ISCELL
  logical_power universal_gnd *
  page177_i126
#CELL
  pure_quanta q_res *
  page177_i127
#ISCELL
  logical_power universal_gnd *
  page177_i128
#ISCELL
  standard offpage *
  page177_i13
#ISCELL
  standard offpage *
  page177_i15
#ISCELL
  standard offpage *
  page177_i16
#ISCELL
  standard offpage *
  page177_i18
#ISCELL
  standard offpage *
  page177_i19
#ISCELL
  standard offpage *
  page177_i2
#ISCELL
  standard offpage *
  page177_i21
#ISCELL
  standard offpage *
  page177_i22
#ISCELL
  standard offpage *
  page177_i23
#CELL
  pure_quanta q_res *
  page177_i24
#ISCELL
  logical_power universal_power *
  page177_i25
#CELL
  pure_quanta emmitsburg_rev0p9 *
  page177_i27
#ISCELL
  standard offpage *
  page177_i3
#ISCELL
  standard offpage *
  page177_i33
#ISCELL
  standard offpage *
  page177_i34
#ISCELL
  standard offpage *
  page177_i35
#ISCELL
  standard offpage *
  page177_i39
#ISCELL
  logical_power universal_power *
  page177_i53
#ISCELL
  logical_power universal_power *
  page177_i56
#ISCELL
  standard offpage *
  page177_i57
#ISCELL
  logical_power universal_power *
  page177_i59
#CELL
  pure_quanta q_res *
  page177_i62
#CELL
  pure_quanta conn2_aaabat029y19 *
  page177_i63
#CELL
  pure_quanta bas70057f *
  page177_i64
#CELL
  pure_quanta q_cap *
  page177_i65
#ISCELL
  logical_power universal_gnd *
  page177_i66
#ISCELL
  logical_power universal_gnd *
  page177_i67
#CELL
  pure_quanta q_cap *
  page177_i68
#ISCELL
  logical_power universal_gnd *
  page177_i69
#CELL
  pure_quanta q_res *
  page177_i70
#ISCELL
  standard offpage *
  page177_i71
#ISCELL
  standard offpage *
  page177_i73
#ISCELL
  standard offpage *
  page177_i74
#ISCELL
  standard offpage *
  page177_i75
#ISCELL
  standard offpage *
  page177_i76
#ISCELL
  standard offpage *
  page177_i78
#ISCELL
  standard offpage *
  page177_i79
#CELL
  pure_quanta q_res *
  page177_i80
#ISCELL
  standard offpage *
  page177_i82
#ISCELL
  logical_power universal_gnd *
  page177_i83
#ISCELL
  standard offpage *
  page177_i84
#CELL
  pure_quanta q_res *
  page177_i85
#ISCELL
  standard offpage *
  page177_i87
#ISCELL
  logical_power universal_gnd *
  page177_i88
#CELL
  pure_quanta q_res *
  page177_i89
#ISCELL
  standard offpage *
  page177_i90
#ISCELL
  standard offpage *
  page177_i92
#ISCELL
  standard offpage *
  page177_i93
#ISCELL
  standard offpage *
  page177_i95
#ISCELL
  standard offpage *
  page177_i96
#ISCELL
  standard offpage *
  page177_i97
#ISCELL
  standard offpage *
  page177_i98
#ISCELL
  standard offpage *
  page177_i99
